(kicad_pcb
	(version 20241229)
	(generator "pcbnew")
	(generator_version "9.0")
	(general
		(thickness 1.63)
		(legacy_teardrops no)
	)
	(paper "A4")
	(title_block
		(title "CM4 Baseboard")
		(date "2026-01-05")
		(rev "1.1.1")
		(company "Antmicro Ltd")
		(comment 1 "www.antmicro.com")
		(comment 9 "footprints 303-306 of 506")
	)
	(layers
		(0 "F.Cu" signal)
		(4 "In1.Cu" power)
		(6 "In2.Cu" power)
		(8 "In3.Cu" signal)
		(10 "In4.Cu" signal)
		(2 "B.Cu" signal)
		(9 "F.Adhes" user "F.Adhesive")
		(11 "B.Adhes" user "B.Adhesive")
		(13 "F.Paste" user)
		(15 "B.Paste" user)
		(5 "F.SilkS" user "F.Silkscreen")
		(7 "B.SilkS" user "B.Silkscreen")
		(1 "F.Mask" user)
		(3 "B.Mask" user)
		(17 "Dwgs.User" user "User.Drawings")
		(19 "Cmts.User" user "User.Comments")
		(21 "Eco1.User" user "User.Eco1")
		(23 "Eco2.User" user "User.Eco2")
		(25 "Edge.Cuts" user)
		(27 "Margin" user)
		(31 "F.CrtYd" user "F.Courtyard")
		(29 "B.CrtYd" user "B.Courtyard")
		(35 "F.Fab" user)
		(33 "B.Fab" user)
	)
	(footprint "antmicro-footprints:C_0402_1005Metric"
		(layer "F.Cu")
		(at 65.092962 175.7005 -90)
		(descr "Capacitor SMD 0402")
		(tags "capacitor SMD 0402")
		(property "Reference" "C819"
			(at -3.504 13.925 90)
			(layer "F.SilkS")
			(effects
				(font
					(size 0.7 0.7)
					(thickness 0.15)
				)
				(justify right bottom)
			)
		)
		(property "Value" "C_470p_100V_0402"
			(at -1.022927 2.155213 90)
			(layer "F.Fab")
			(effects
				(font
					(size 0.7 0.7)
					(thickness 0.15)
				)
				(justify right bottom)
			)
		)
		(property "Datasheet" "https://search.murata.co.jp/Ceramy/image/img/A01X/G101/ENG/GRM1555C2A471JE01-01A.pdf"
			(at 0 0 270)
			(layer "F.Fab")
			(hide yes)
			(effects
				(font
					(size 1.27 1.27)
					(thickness 0.15)
				)
			)
		)
		(property "Description" "MLCC, SMD/SMT, 100V, 470pF, C0G/NP0, 0402 5%"
			(at 0 0 270)
			(layer "F.Fab")
			(hide yes)
			(effects
				(font
					(size 1.27 1.27)
					(thickness 0.15)
				)
			)
		)
		(property "MPN" "GRM1555C2A471JE01D"
			(at 0 0 270)
			(unlocked yes)
			(layer "F.Fab")
			(hide yes)
			(effects
				(font
					(size 1 1)
					(thickness 0.15)
				)
			)
		)
		(property "Manufacturer" "Murata"
			(at 0 0 270)
			(unlocked yes)
			(layer "F.Fab")
			(hide yes)
			(effects
				(font
					(size 1 1)
					(thickness 0.15)
				)
			)
		)
		(property "License" "Apache-2.0"
			(at 0 0 270)
			(unlocked yes)
			(layer "F.Fab")
			(hide yes)
			(effects
				(font
					(size 1 1)
					(thickness 0.15)
				)
			)
		)
		(property "Author" "Antmicro"
			(at 0 0 270)
			(unlocked yes)
			(layer "F.Fab")
			(hide yes)
			(effects
				(font
					(size 1 1)
					(thickness 0.15)
				)
			)
		)
		(property "Val" "470p"
			(at 0 0 270)
			(unlocked yes)
			(layer "F.Fab")
			(hide yes)
			(effects
				(font
					(size 1 1)
					(thickness 0.15)
				)
			)
		)
		(property "Voltage" "100V"
			(at 0 0 270)
			(unlocked yes)
			(layer "F.Fab")
			(hide yes)
			(effects
				(font
					(size 1 1)
					(thickness 0.15)
				)
			)
		)
		(property "Dielectric" "C0G/NP0"
			(at 0 0 270)
			(unlocked yes)
			(layer "F.Fab")
			(hide yes)
			(effects
				(font
					(size 1 1)
					(thickness 0.15)
				)
			)
		)
		(sheetname "/Peripherals/")
		(sheetfile "peripherals.kicad_sch")
		(attr smd)
		(fp_rect
			(start -0.925 -0.47)
			(end 0.925 0.47)
			(stroke
				(width 0.05)
				(type default)
			)
			(fill no)
			(layer "F.CrtYd")
		)
		(fp_line
			(start -0.494 0.248)
			(end -0.494 -0.25)
			(stroke
				(width 0.15)
				(type solid)
			)
			(layer "F.Fab")
		)
		(fp_line
			(start 0.504 0.248)
			(end -0.494 0.248)
			(stroke
				(width 0.15)
				(type solid)
			)
			(layer "F.Fab")
		)
		(fp_line
			(start -0.494 -0.25)
			(end 0.504 -0.25)
			(stroke
				(width 0.15)
				(type solid)
			)
			(layer "F.Fab")
		)
		(fp_line
			(start 0.504 -0.25)
			(end 0.504 0.248)
			(stroke
				(width 0.15)
				(type solid)
			)
			(layer "F.Fab")
		)
		(fp_text user "Author: Antmicro"
			(at -0.939 3.399 270)
			(layer "F.Fab")
			(effects
				(font
					(size 0.7 0.7)
					(thickness 0.15)
				)
				(justify left bottom)
			)
		)
		(fp_text user "${REFERENCE}"
			(at -0.939 4.599 270)
			(layer "F.Fab")
			(effects
				(font
					(size 0.7 0.7)
					(thickness 0.15)
				)
				(justify left bottom)
			)
		)
		(fp_text user "License: Apache-2.0"
			(at -0.939 5.799 270)
			(layer "F.Fab")
			(effects
				(font
					(size 0.7 0.7)
					(thickness 0.15)
				)
				(justify left bottom)
			)
		)
		(pad "1" smd roundrect
			(at -0.48 0 270)
			(size 0.59 0.64)
			(layers "F.Cu" "F.Mask" "F.Paste")
			(roundrect_rratio 0.25)
			(net 110 "Net-(C817-Pad1)")
			(pintype "passive")
		)
		(pad "2" smd roundrect
			(at 0.48 0 270)
			(size 0.59 0.64)
			(layers "F.Cu" "F.Mask" "F.Paste")
			(roundrect_rratio 0.25)
			(net 3 "GND")
			(pintype "passive")
		)
	)
	(footprint "antmicro-footprints:C_0402_1005Metric"
		(layer "F.Cu")
		(at 97.717962 142.7165 180)
		(descr "Capacitor SMD 0402")
		(tags "capacitor SMD 0402")
		(property "Reference" "C935"
			(at -4.15 0.45 0)
			(layer "F.SilkS")
			(effects
				(font
					(size 0.7 0.7)
					(thickness 0.15)
				)
				(justify right bottom)
			)
		)
		(property "Value" "C_100n_0402"
			(at -1.022927 2.155213 0)
			(layer "F.Fab")
			(effects
				(font
					(size 0.7 0.7)
					(thickness 0.15)
				)
				(justify right bottom)
			)
		)
		(property "Datasheet" "https://www.murata.com/products/productdetail?partno=GRM155R61H104KE14%23"
			(at 0 0 180)
			(layer "F.Fab")
			(hide yes)
			(effects
				(font
					(size 1.27 1.27)
					(thickness 0.15)
				)
			)
		)
		(property "MPN" "GRM155R61H104KE14D"
			(at 0 0 180)
			(unlocked yes)
			(layer "F.Fab")
			(hide yes)
			(effects
				(font
					(size 1 1)
					(thickness 0.15)
				)
			)
		)
		(property "Manufacturer" "Murata"
			(at 0 0 180)
			(unlocked yes)
			(layer "F.Fab")
			(hide yes)
			(effects
				(font
					(size 1 1)
					(thickness 0.15)
				)
			)
		)
		(property "License" "Apache-2.0"
			(at 0 0 180)
			(unlocked yes)
			(layer "F.Fab")
			(hide yes)
			(effects
				(font
					(size 1 1)
					(thickness 0.15)
				)
			)
		)
		(property "Author" "Antmicro"
			(at 0 0 180)
			(unlocked yes)
			(layer "F.Fab")
			(hide yes)
			(effects
				(font
					(size 1 1)
					(thickness 0.15)
				)
			)
		)
		(property "Val" "100n"
			(at 0 0 180)
			(unlocked yes)
			(layer "F.Fab")
			(hide yes)
			(effects
				(font
					(size 1 1)
					(thickness 0.15)
				)
			)
		)
		(property "Voltage" "50V"
			(at 0 0 180)
			(unlocked yes)
			(layer "F.Fab")
			(hide yes)
			(effects
				(font
					(size 1 1)
					(thickness 0.15)
				)
			)
		)
		(property "Dielectric" "X5R"
			(at 0 0 180)
			(unlocked yes)
			(layer "F.Fab")
			(hide yes)
			(effects
				(font
					(size 1 1)
					(thickness 0.15)
				)
			)
		)
		(sheetname "/USB/")
		(sheetfile "usb.kicad_sch")
		(attr smd)
		(fp_rect
			(start -0.925 -0.47)
			(end 0.925 0.47)
			(stroke
				(width 0.05)
				(type default)
			)
			(fill no)
			(layer "F.CrtYd")
		)
		(fp_line
			(start 0.504 0.248)
			(end -0.494 0.248)
			(stroke
				(width 0.15)
				(type solid)
			)
			(layer "F.Fab")
		)
		(fp_line
			(start 0.504 -0.25)
			(end 0.504 0.248)
			(stroke
				(width 0.15)
				(type solid)
			)
			(layer "F.Fab")
		)
		(fp_line
			(start -0.494 0.248)
			(end -0.494 -0.25)
			(stroke
				(width 0.15)
				(type solid)
			)
			(layer "F.Fab")
		)
		(fp_line
			(start -0.494 -0.25)
			(end 0.504 -0.25)
			(stroke
				(width 0.15)
				(type solid)
			)
			(layer "F.Fab")
		)
		(fp_text user "${REFERENCE}"
			(at -0.939 4.599 180)
			(layer "F.Fab")
			(effects
				(font
					(size 0.7 0.7)
					(thickness 0.15)
				)
				(justify left bottom)
			)
		)
		(fp_text user "Author: Antmicro"
			(at -0.939 3.399 180)
			(layer "F.Fab")
			(effects
				(font
					(size 0.7 0.7)
					(thickness 0.15)
				)
				(justify left bottom)
			)
		)
		(fp_text user "License: Apache-2.0"
			(at -0.939 5.799 180)
			(layer "F.Fab")
			(effects
				(font
					(size 0.7 0.7)
					(thickness 0.15)
				)
				(justify left bottom)
			)
		)
		(pad "1" smd roundrect
			(at -0.48 0 180)
			(size 0.59 0.64)
			(layers "F.Cu" "F.Mask" "F.Paste")
			(roundrect_rratio 0.25)
			(net 3 "GND")
			(pintype "passive")
		)
		(pad "2" smd roundrect
			(at 0.48 0 180)
			(size 0.59 0.64)
			(layers "F.Cu" "F.Mask" "F.Paste")
			(roundrect_rratio 0.25)
			(net 9 "+3V3")
			(pintype "passive")
		)
	)
	(footprint "antmicro-footprints:R_0402_1005Metric"
		(layer "F.Cu")
		(at 140.852962 126.4565 180)
		(descr "Resistor SMD 0402")
		(tags "resistor SMD 0402")
		(property "Reference" "R214"
			(at 0.802962 -0.5185 0)
			(layer "F.SilkS")
			(effects
				(font
					(size 0.7 0.7)
					(thickness 0.15)
				)
				(justify right bottom)
			)
		)
		(property "Value" "R_100k_0402"
			(at -1.011843 1.772047 0)
			(layer "F.Fab")
			(effects
				(font
					(size 0.7 0.7)
					(thickness 0.15)
				)
				(justify right bottom)
			)
		)
		(property "Datasheet" "https://www.bourns.com/docs/product-datasheets/cr.pdf"
			(at 0 0 180)
			(layer "F.Fab")
			(hide yes)
			(effects
				(font
					(size 1.27 1.27)
					(thickness 0.15)
				)
			)
		)
		(property "Manufacturer" "Bourns"
			(at 0 0 180)
			(unlocked yes)
			(layer "F.Fab")
			(hide yes)
			(effects
				(font
					(size 1 1)
					(thickness 0.15)
				)
			)
		)
		(property "MPN" "CR0402-FX-1003GLF"
			(at 0 0 180)
			(unlocked yes)
			(layer "F.Fab")
			(hide yes)
			(effects
				(font
					(size 1 1)
					(thickness 0.15)
				)
			)
		)
		(property "Val" "100k"
			(at 0 0 180)
			(unlocked yes)
			(layer "F.Fab")
			(hide yes)
			(effects
				(font
					(size 1 1)
					(thickness 0.15)
				)
			)
		)
		(property "License" "Apache-2.0"
			(at 0 0 180)
			(unlocked yes)
			(layer "F.Fab")
			(hide yes)
			(effects
				(font
					(size 1 1)
					(thickness 0.15)
				)
			)
		)
		(property "Author" "Antmicro"
			(at 0 0 180)
			(unlocked yes)
			(layer "F.Fab")
			(hide yes)
			(effects
				(font
					(size 1 1)
					(thickness 0.15)
				)
			)
		)
		(property "Tolerance" "1%"
			(at 0 0 180)
			(unlocked yes)
			(layer "F.Fab")
			(hide yes)
			(effects
				(font
					(size 1 1)
					(thickness 0.15)
				)
			)
		)
		(sheetname "/Compute module/")
		(sheetfile "compute-module.kicad_sch")
		(attr smd)
		(fp_rect
			(start -0.925 -0.47)
			(end 0.925 0.47)
			(stroke
				(width 0.05)
				(type default)
			)
			(fill no)
			(layer "F.CrtYd")
		)
		(fp_rect
			(start -0.5 -0.25)
			(end 0.5 0.25)
			(stroke
				(width 0.15)
				(type solid)
			)
			(fill no)
			(layer "F.Fab")
		)
		(fp_text user "${REFERENCE}"
			(at -0.95 3.168 180)
			(layer "F.Fab")
			(effects
				(font
					(size 0.7 0.7)
					(thickness 0.15)
				)
				(justify left bottom)
			)
		)
		(fp_text user "License: Apache-2.0"
			(at -0.95 5.169 180)
			(layer "F.Fab")
			(effects
				(font
					(size 0.7 0.7)
					(thickness 0.15)
				)
				(justify left bottom)
			)
		)
		(fp_text user "Author: Antmicro"
			(at -0.95 4.169 180)
			(layer "F.Fab")
			(effects
				(font
					(size 0.7 0.7)
					(thickness 0.15)
				)
				(justify left bottom)
			)
		)
		(pad "1" smd roundrect
			(at -0.48 0 180)
			(size 0.59 0.64)
			(layers "F.Cu" "F.Mask" "F.Paste")
			(roundrect_rratio 0.25)
			(net 329 "Net-(Q207-G)")
			(pintype "passive")
		)
		(pad "2" smd roundrect
			(at 0.48 0 180)
			(size 0.59 0.64)
			(layers "F.Cu" "F.Mask" "F.Paste")
			(roundrect_rratio 0.25)
			(net 3 "GND")
			(pintype "passive")
		)
	)
	(footprint "antmicro-footprints:C_0402_1005Metric"
		(layer "F.Cu")
		(at 101.192962 131.9915)
		(descr "Capacitor SMD 0402")
		(tags "capacitor SMD 0402")
		(property "Reference" "C931"
			(at 0.935 0.425 180)
			(layer "F.SilkS")
			(effects
				(font
					(size 0.7 0.7)
					(thickness 0.15)
				)
				(justify left bottom)
			)
		)
		(property "Value" "C_1u_25V_0402"
			(at -1.022927 2.155213 0)
			(layer "F.Fab")
			(effects
				(font
					(size 0.7 0.7)
					(thickness 0.15)
				)
				(justify left bottom)
			)
		)
		(property "Datasheet" "https://www.murata.com/products/productdetail?partno=GRM155R61E105KE11%23"
			(at 0 0 0)
			(layer "F.Fab")
			(hide yes)
			(effects
				(font
					(size 1.27 1.27)
					(thickness 0.15)
				)
			)
		)
		(property "MPN" "GRM155R61E105KE11J"
			(at 0 0 0)
			(unlocked yes)
			(layer "F.Fab")
			(hide yes)
			(effects
				(font
					(size 1 1)
					(thickness 0.15)
				)
			)
		)
		(property "Manufacturer" "Murata"
			(at 0 0 0)
			(unlocked yes)
			(layer "F.Fab")
			(hide yes)
			(effects
				(font
					(size 1 1)
					(thickness 0.15)
				)
			)
		)
		(property "License" "Apache-2.0"
			(at 0 0 0)
			(unlocked yes)
			(layer "F.Fab")
			(hide yes)
			(effects
				(font
					(size 1 1)
					(thickness 0.15)
				)
			)
		)
		(property "Author" "Antmicro"
			(at 0 0 0)
			(unlocked yes)
			(layer "F.Fab")
			(hide yes)
			(effects
				(font
					(size 1 1)
					(thickness 0.15)
				)
			)
		)
		(property "Val" "1u"
			(at 0 0 0)
			(unlocked yes)
			(layer "F.Fab")
			(hide yes)
			(effects
				(font
					(size 1 1)
					(thickness 0.15)
				)
			)
		)
		(property "Voltage" "25V"
			(at 0 0 0)
			(unlocked yes)
			(layer "F.Fab")
			(hide yes)
			(effects
				(font
					(size 1 1)
					(thickness 0.15)
				)
			)
		)
		(property "Dielectric" "X5R"
			(at 0 0 0)
			(unlocked yes)
			(layer "F.Fab")
			(hide yes)
			(effects
				(font
					(size 1 1)
					(thickness 0.15)
				)
			)
		)
		(sheetname "/USB/")
		(sheetfile "usb.kicad_sch")
		(attr smd)
		(fp_rect
			(start -0.925 -0.47)
			(end 0.925 0.47)
			(stroke
				(width 0.05)
				(type default)
			)
			(fill no)
			(layer "F.CrtYd")
		)
		(fp_line
			(start -0.494 -0.25)
			(end 0.504 -0.25)
			(stroke
				(width 0.15)
				(type solid)
			)
			(layer "F.Fab")
		)
		(fp_line
			(start -0.494 0.248)
			(end -0.494 -0.25)
			(stroke
				(width 0.15)
				(type solid)
			)
			(layer "F.Fab")
		)
		(fp_line
			(start 0.504 -0.25)
			(end 0.504 0.248)
			(stroke
				(width 0.15)
				(type solid)
			)
			(layer "F.Fab")
		)
		(fp_line
			(start 0.504 0.248)
			(end -0.494 0.248)
			(stroke
				(width 0.15)
				(type solid)
			)
			(layer "F.Fab")
		)
		(fp_text user "License: Apache-2.0"
			(at -0.939 5.799 0)
			(layer "F.Fab")
			(effects
				(font
					(size 0.7 0.7)
					(thickness 0.15)
				)
				(justify left bottom)
			)
		)
		(fp_text user "Author: Antmicro"
			(at -0.939 3.399 0)
			(layer "F.Fab")
			(effects
				(font
					(size 0.7 0.7)
					(thickness 0.15)
				)
				(justify left bottom)
			)
		)
		(fp_text user "${REFERENCE}"
			(at -0.939 4.599 0)
			(layer "F.Fab")
			(effects
				(font
					(size 0.7 0.7)
					(thickness 0.15)
				)
				(justify left bottom)
			)
		)
		(pad "1" smd roundrect
			(at -0.48 0)
			(size 0.59 0.64)
			(layers "F.Cu" "F.Mask" "F.Paste")
			(roundrect_rratio 0.25)
			(net 127 "Net-(Q903-G)")
			(pintype "passive")
		)
		(pad "2" smd roundrect
			(at 0.48 0)
			(size 0.59 0.64)
			(layers "F.Cu" "F.Mask" "F.Paste")
			(roundrect_rratio 0.25)
			(net 10 "+5V")
			(pintype "passive")
		)
	)
)
